# S9S_MB_2U (Grand Teton) — schematic netlist excerpt (pin names and nets, part order shuffled) for the footprints in the layout excerpt that follows; sources: Cadence DE-HDL packaged netlist, KiCad conversion of 03242023_DA0F0TMBIJ0_F0T_Motherboard_J_brd_V01_OCP.brd

J64  PICOPROBE_BXA  DELTA-L 4.0 EMPTY  pkg TRIANG_LAUNCH_3PXB  page 308
  \1_p\  = DELTA_L_85_5INCH_BOT_DP
  \2_n\  = DELTA_L_85_5INCH_BOT_DN
  \3_g\  = DELTA_L_GND_1

C333  Q_CAP  47UF 4V 20% X6S  pkg C0805  page 78 : A = PVCCIN_CPU1 ; B = GND

(kicad_pcb
	(version 20260206)
	(generator "pcbnew")
	(generator_version "10.0")
	(general
		(thickness 1.6)
		(legacy_teardrops no)
	)
	(paper "A4")
	(title_block
		(title "03242023_DA0F0TMBIJ0_F0T_Motherboard_J_brd_V01_OCP.brd")
		(comment 1 "Grand Teton / footprints 5762-5763 of 6105")
	)
	(layers
		(0 "F.Cu" signal "TOP")
		(4 "In1.Cu" signal "GND")
		(6 "In2.Cu" signal "IN1")
		(8 "In3.Cu" signal "GND1")
		(10 "In4.Cu" signal "IN2")
		(12 "In5.Cu" signal "GND2")
		(14 "In6.Cu" signal "IN3")
		(16 "In7.Cu" signal "GND3")
		(18 "In8.Cu" signal "VCC")
		(20 "In9.Cu" signal "VCC1")
		(22 "In10.Cu" signal "GND4")
		(24 "In11.Cu" signal "IN4")
		(26 "In12.Cu" signal "GND5")
		(28 "In13.Cu" signal "IN5")
		(30 "In14.Cu" signal "GND6")
		(32 "In15.Cu" signal "IN6")
		(34 "In16.Cu" signal "GND7")
		(2 "B.Cu" signal "BOTTOM")
		(9 "F.Adhes" user "F.Adhesive")
		(11 "B.Adhes" user "B.Adhesive")
		(13 "F.Paste" user "Package Geometry/Pastemask Top")
		(15 "B.Paste" user "Package Geometry/Pastemask Bottom")
		(5 "F.SilkS" user "Ref Des/Silkscreen Top")
		(7 "B.SilkS" user "Ref Des/Silkscreen Bottom")
		(1 "F.Mask" user "Board Geometry/Soldermask Top")
		(3 "B.Mask" user "Board Geometry/Soldermask Bottom")
		(17 "Dwgs.User" user "User.Drawings")
		(19 "Cmts.User" user "User.Comments")
		(21 "Eco1.User" user "User.Eco1")
		(23 "Eco2.User" user "User.Eco2")
		(25 "Edge.Cuts" user "Board Geometry/Outline")
		(27 "Margin" user)
		(31 "F.CrtYd" user "Package Geometry/Place Bound Top")
		(29 "B.CrtYd" user "Package Geometry/Place Bound Bottom")
		(35 "F.Fab" user "Ref Des/Assembly Top")
		(33 "B.Fab" user "Ref Des/Assembly Bottom")
	)
	(footprint ""
		(layer "B.Cu")
		(at 378.099574 -2.156206)
		(property "Reference" "J64"
			(at 4.651756 1.013206 270)
			(unlocked yes)
			(layer "B.SilkS")
			(effects
				(font
					(size 0.7874 0.5842)
					(thickness 0.1524)
				)
				(justify left mirror)
			)
		)
		(property "Value" ""
			(at 0 0 0)
			(layer "B.Fab")
			(effects
				(font
					(size 1.27 1.27)
				)
				(justify mirror)
			)
		)
		(duplicate_pad_numbers_are_jumpers no)
		(fp_line
			(start -1.2192 -2.1082)
			(end -1.2192 2.1082)
			(stroke
				(width 0.1524)
				(type default)
			)
			(layer "B.SilkS")
		)
		(fp_line
			(start -1.2192 2.1082)
			(end 1.2192 2.1082)
			(stroke
				(width 0.1524)
				(type default)
			)
			(layer "B.SilkS")
		)
		(fp_line
			(start 1.2192 -2.1082)
			(end -1.2192 -2.1082)
			(stroke
				(width 0.1524)
				(type default)
			)
			(layer "B.SilkS")
		)
		(fp_line
			(start 1.2192 2.1082)
			(end 1.2192 -2.1082)
			(stroke
				(width 0.1524)
				(type default)
			)
			(layer "B.SilkS")
		)
		(pad "" np_thru_hole circle
			(at -3.4671 -1.27 270)
			(size 1.0414 1.0414)
			(drill 1.0414)
			(layers "*.Cu" "*.Mask")
			(clearance 0.381)
			(thermal_gap 0.381)
		)
		(pad "" np_thru_hole circle
			(at -3.4671 1.27 270)
			(size 1.0414 1.0414)
			(drill 1.0414)
			(layers "*.Cu" "*.Mask")
			(clearance 0.381)
			(thermal_gap 0.381)
		)
		(pad "" np_thru_hole circle
			(at 2.8829 -1.27 270)
			(size 1.0414 1.0414)
			(drill 1.0414)
			(layers "*.Cu" "*.Mask")
			(clearance 0.381)
			(thermal_gap 0.381)
		)
		(pad "" np_thru_hole circle
			(at 2.8829 1.27 270)
			(size 1.0414 1.0414)
			(drill 1.0414)
			(layers "*.Cu" "*.Mask")
			(clearance 0.381)
			(thermal_gap 0.381)
		)
		(pad "1" smd rect
			(at -0.8255 -0.249936 270)
			(size 0.3048 0.508)
			(layers "B.Cu" "B.Mask" "B.Paste")
			(net "DELTA_L_85_5INCH_BOT_DP")
		)
		(pad "2" smd rect
			(at -0.8255 0.249936 270)
			(size 0.3048 0.508)
			(layers "B.Cu" "B.Mask" "B.Paste")
			(net "DELTA_L_85_5INCH_BOT_DN")
		)
		(pad "3" smd circle
			(at 0 0 180)
			(size 0 0)
			(layers "B.Cu" "B.Mask" "B.Paste")
			(net "DELTA_L_GND_1")
		)
		(zone
			(layers "F.Cu" "B.Cu" "In1.Cu" "In2.Cu" "In3.Cu" "In4.Cu" "In5.Cu" "In6.Cu"
				"In7.Cu" "In8.Cu" "In9.Cu" "In10.Cu" "In11.Cu" "In12.Cu" "In13.Cu" "In14.Cu"
				"In15.Cu" "In16.Cu"
			)
			(hatch none 0.5)
			(connect_pads
				(clearance 0)
			)
			(min_thickness 0.25)
			(keepout
				(tracks not_allowed)
				(vias allowed)
				(pads allowed)
				(copperpour not_allowed)
				(footprints allowed)
			)
			(placement
				(enabled no)
				(sheetname "")
			)
			(fill
				(thermal_gap 0.5)
				(thermal_bridge_width 0.5)
				(island_removal_mode 0)
			)
			(polygon
				(pts
					(arc
						(start 375.559574 -3.426206)
						(mid 373.705374 -3.426206)
						(end 375.559574 -3.426206)
					)
				)
			)
		)
		(zone
			(layers "F.Cu" "B.Cu" "In1.Cu" "In2.Cu" "In3.Cu" "In4.Cu" "In5.Cu" "In6.Cu"
				"In7.Cu" "In8.Cu" "In9.Cu" "In10.Cu" "In11.Cu" "In12.Cu" "In13.Cu" "In14.Cu"
				"In15.Cu" "In16.Cu"
			)
			(hatch none 0.5)
			(connect_pads
				(clearance 0)
			)
			(min_thickness 0.25)
			(keepout
				(tracks not_allowed)
				(vias allowed)
				(pads allowed)
				(copperpour not_allowed)
				(footprints allowed)
			)
			(placement
				(enabled no)
				(sheetname "")
			)
			(fill
				(thermal_gap 0.5)
				(thermal_bridge_width 0.5)
				(island_removal_mode 0)
			)
			(polygon
				(pts
					(arc
						(start 375.559574 -0.886206)
						(mid 373.705374 -0.886206)
						(end 375.559574 -0.886206)
					)
				)
			)
		)
		(zone
			(layers "F.Cu" "B.Cu" "In1.Cu" "In2.Cu" "In3.Cu" "In4.Cu" "In5.Cu" "In6.Cu"
				"In7.Cu" "In8.Cu" "In9.Cu" "In10.Cu" "In11.Cu" "In12.Cu" "In13.Cu" "In14.Cu"
				"In15.Cu" "In16.Cu"
			)
			(hatch none 0.5)
			(connect_pads
				(clearance 0)
			)
			(min_thickness 0.25)
			(keepout
				(tracks not_allowed)
				(vias allowed)
				(pads allowed)
				(copperpour not_allowed)
				(footprints allowed)
			)
			(placement
				(enabled no)
				(sheetname "")
			)
			(fill
				(thermal_gap 0.5)
				(thermal_bridge_width 0.5)
				(island_removal_mode 0)
			)
			(polygon
				(pts
					(arc
						(start 381.909574 -3.426206)
						(mid 380.055374 -3.426206)
						(end 381.909574 -3.426206)
					)
				)
			)
		)
		(zone
			(layers "F.Cu" "B.Cu" "In1.Cu" "In2.Cu" "In3.Cu" "In4.Cu" "In5.Cu" "In6.Cu"
				"In7.Cu" "In8.Cu" "In9.Cu" "In10.Cu" "In11.Cu" "In12.Cu" "In13.Cu" "In14.Cu"
				"In15.Cu" "In16.Cu"
			)
			(hatch none 0.5)
			(connect_pads
				(clearance 0)
			)
			(min_thickness 0.25)
			(keepout
				(tracks not_allowed)
				(vias allowed)
				(pads allowed)
				(copperpour not_allowed)
				(footprints allowed)
			)
			(placement
				(enabled no)
				(sheetname "")
			)
			(fill
				(thermal_gap 0.5)
				(thermal_bridge_width 0.5)
				(island_removal_mode 0)
			)
			(polygon
				(pts
					(arc
						(start 381.909574 -0.886206)
						(mid 380.055374 -0.886206)
						(end 381.909574 -0.886206)
					)
				)
			)
		)
		(zone
			(layer "B.Cu")
			(hatch none 0.5)
			(connect_pads
				(clearance 0)
			)
			(min_thickness 0.25)
			(keepout
				(tracks not_allowed)
				(vias allowed)
				(pads allowed)
				(copperpour not_allowed)
				(footprints allowed)
			)
			(placement
				(enabled no)
				(sheetname "")
			)
			(fill
				(thermal_gap 0.5)
				(thermal_bridge_width 0.5)
				(island_removal_mode 0)
			)
			(polygon
				(pts
					(xy 376.981974 -2.704846) (xy 376.981974 -2.609342) (xy 377.578874 -2.609342) (xy 377.578874 -2.202942)
					(xy 376.981974 -2.202942) (xy 376.981974 -2.10947) (xy 377.578874 -2.10947) (xy 377.578874 -1.70307)
					(xy 376.981974 -1.70307) (xy 376.981974 -1.607566) (xy 377.680474 -1.607566) (xy 377.680474 -2.704846)
				)
			)
		)
	)
	(footprint ""
		(layer "B.Cu")
		(at 107.457494 -252.17628 -90)
		(property "Reference" "C333"
			(at 0 0 90)
			(layer "B.SilkS")
			(hide yes)
			(effects
				(font
					(size 1.27 1.27)
				)
				(justify mirror)
			)
		)
		(property "Value" ""
			(at 0 0 90)
			(layer "B.Fab")
			(effects
				(font
					(size 1.27 1.27)
				)
				(justify mirror)
			)
		)
		(duplicate_pad_numbers_are_jumpers no)
		(fp_line
			(start -1.524 0.762)
			(end 1.524 0.762)
			(stroke
				(width 0.1524)
				(type default)
			)
			(layer "B.SilkS")
		)
		(fp_line
			(start 1.524 0.762)
			(end 1.524 -0.762)
			(stroke
				(width 0.1524)
				(type default)
			)
			(layer "B.SilkS")
		)
		(fp_line
			(start -1.524 -0.762)
			(end -1.524 0.762)
			(stroke
				(width 0.1524)
				(type default)
			)
			(layer "B.SilkS")
		)
		(fp_line
			(start 1.524 -0.762)
			(end -1.524 -0.762)
			(stroke
				(width 0.1524)
				(type default)
			)
			(layer "B.SilkS")
		)
		(fp_line
			(start -1.1049 0.724916)
			(end -1.1049 -0.724916)
			(stroke
				(width 0.1)
				(type default)
			)
			(layer "B.Fab")
		)
		(fp_line
			(start 1.1049 0.724916)
			(end -1.1049 0.724916)
			(stroke
				(width 0.1)
				(type default)
			)
			(layer "B.Fab")
		)
		(fp_line
			(start -1.1049 -0.724916)
			(end 1.1049 -0.724916)
			(stroke
				(width 0.1)
				(type default)
			)
			(layer "B.Fab")
		)
		(fp_line
			(start 1.1049 -0.724916)
			(end 1.1049 0.724916)
			(stroke
				(width 0.1)
				(type default)
			)
			(layer "B.Fab")
		)
		(pad "1" smd rect
			(at 0.889 0 270)
			(size 1.016 1.27)
			(layers "B.Cu" "B.Mask" "B.Paste")
			(net "PVCCIN_CPU1")
		)
		(pad "2" smd rect
			(at -0.889 0 270)
			(size 1.016 1.27)
			(layers "B.Cu" "B.Mask" "B.Paste")
			(net "GND")
		)
	)
)
